(kicad_pcb
	(version 20260206)
	(generator "pcbnew")
	(generator_version "10.0")
	(general
		(thickness 1.6)
		(legacy_teardrops no)
	)
	(paper "A4")
	(title_block
		(title "04192023_DAF0TMB3IC0_F0TG_MB_C_brd_V02_OCP.brd")
		(comment 1 "Grand Teton / footprints 4864-4870 of 8354")
	)
	(layers
		(0 "F.Cu" signal "TOP")
		(4 "In1.Cu" signal "GND")
		(6 "In2.Cu" signal "IN1")
		(8 "In3.Cu" signal "GND1")
		(10 "In4.Cu" signal "IN2")
		(12 "In5.Cu" signal "GND2")
		(14 "In6.Cu" signal "IN3")
		(16 "In7.Cu" signal "GND3")
		(18 "In8.Cu" signal "VCC")
		(20 "In9.Cu" signal "VCC1")
		(22 "In10.Cu" signal "GND4")
		(24 "In11.Cu" signal "IN4")
		(26 "In12.Cu" signal "GND5")
		(28 "In13.Cu" signal "IN5")
		(30 "In14.Cu" signal "GND6")
		(32 "In15.Cu" signal "IN6")
		(34 "In16.Cu" signal "GND7")
		(2 "B.Cu" signal "BOTTOM")
		(9 "F.Adhes" user "F.Adhesive")
		(11 "B.Adhes" user "B.Adhesive")
		(13 "F.Paste" user "Package Geometry/Pastemask Top")
		(15 "B.Paste" user "Package Geometry/Pastemask Bottom")
		(5 "F.SilkS" user "Ref Des/Silkscreen Top")
		(7 "B.SilkS" user "Ref Des/Silkscreen Bottom")
		(1 "F.Mask" user "Board Geometry/Soldermask Top")
		(3 "B.Mask" user "Board Geometry/Soldermask Bottom")
		(17 "Dwgs.User" user "User.Drawings")
		(19 "Cmts.User" user "User.Comments")
		(21 "Eco1.User" user "User.Eco1")
		(23 "Eco2.User" user "User.Eco2")
		(25 "Edge.Cuts" user "Board Geometry/Outline")
		(27 "Margin" user)
		(31 "F.CrtYd" user "Package Geometry/Place Bound Top")
		(29 "B.CrtYd" user "Package Geometry/Place Bound Bottom")
		(35 "F.Fab" user "Ref Des/Assembly Top")
		(33 "B.Fab" user "Ref Des/Assembly Bottom")
	)
	(footprint ""
		(layer "F.Cu")
		(at 102.437946 -52.86248 -90)
		(property "Reference" "R6317"
			(at 0 0 270)
			(layer "F.SilkS")
			(hide yes)
			(effects
				(font
					(size 1.27 1.27)
				)
			)
		)
		(property "Value" ""
			(at 0 0 270)
			(layer "F.Fab")
			(effects
				(font
					(size 1.27 1.27)
				)
			)
		)
		(duplicate_pad_numbers_are_jumpers no)
		(fp_line
			(start -0.7874 0.4064)
			(end -0.7874 -0.4064)
			(stroke
				(width 0.1524)
				(type default)
			)
			(layer "F.SilkS")
		)
		(fp_line
			(start 0.7874 0.4064)
			(end -0.7874 0.4064)
			(stroke
				(width 0.1524)
				(type default)
			)
			(layer "F.SilkS")
		)
		(fp_line
			(start -0.7874 -0.4064)
			(end 0.7874 -0.4064)
			(stroke
				(width 0.1524)
				(type default)
			)
			(layer "F.SilkS")
		)
		(fp_line
			(start 0.7874 -0.4064)
			(end 0.7874 0.4064)
			(stroke
				(width 0.1524)
				(type default)
			)
			(layer "F.SilkS")
		)
		(fp_line
			(start -0.67945 0.3048)
			(end -0.67945 -0.305054)
			(stroke
				(width 0.1)
				(type default)
			)
			(layer "F.Fab")
		)
		(fp_line
			(start -0.12065 0.3048)
			(end -0.67945 0.3048)
			(stroke
				(width 0.1)
				(type default)
			)
			(layer "F.Fab")
		)
		(fp_line
			(start 0.120396 0.3048)
			(end 0.120396 0.2794)
			(stroke
				(width 0.1)
				(type default)
			)
			(layer "F.Fab")
		)
		(fp_line
			(start 0.67945 0.3048)
			(end 0.120396 0.3048)
			(stroke
				(width 0.1)
				(type default)
			)
			(layer "F.Fab")
		)
		(fp_line
			(start -0.12065 0.2794)
			(end -0.12065 0.3048)
			(stroke
				(width 0.1)
				(type default)
			)
			(layer "F.Fab")
		)
		(fp_line
			(start 0.120396 0.2794)
			(end -0.12065 0.2794)
			(stroke
				(width 0.1)
				(type default)
			)
			(layer "F.Fab")
		)
		(fp_line
			(start -0.12065 -0.2794)
			(end 0.12065 -0.2794)
			(stroke
				(width 0.1)
				(type default)
			)
			(layer "F.Fab")
		)
		(fp_line
			(start 0.12065 -0.2794)
			(end 0.12065 -0.3048)
			(stroke
				(width 0.1)
				(type default)
			)
			(layer "F.Fab")
		)
		(fp_line
			(start 0.12065 -0.3048)
			(end 0.67945 -0.3048)
			(stroke
				(width 0.1)
				(type default)
			)
			(layer "F.Fab")
		)
		(fp_line
			(start 0.67945 -0.3048)
			(end 0.67945 0.3048)
			(stroke
				(width 0.1)
				(type default)
			)
			(layer "F.Fab")
		)
		(fp_line
			(start -0.67945 -0.305054)
			(end -0.12065 -0.305054)
			(stroke
				(width 0.1)
				(type default)
			)
			(layer "F.Fab")
		)
		(fp_line
			(start -0.12065 -0.305054)
			(end -0.12065 -0.2794)
			(stroke
				(width 0.1)
				(type default)
			)
			(layer "F.Fab")
		)
		(pad "1" smd circle
			(at -0.40005 0 270)
			(size 0 0)
			(layers "F.Cu" "F.Mask" "F.Paste")
			(net "USB_HUB2_MRP_RESET_N")
		)
		(pad "2" smd circle
			(at 0.40005 0 270)
			(size 0 0)
			(layers "F.Cu" "F.Mask" "F.Paste")
			(net "USB_HUB2_TI_USB_VBUS_MRP_RESET_N")
		)
	)
	(footprint ""
		(layer "F.Cu")
		(at 192.53962 -422.804082 -90)
		(property "Reference" "R2946"
			(at 0 0 270)
			(layer "F.SilkS")
			(hide yes)
			(effects
				(font
					(size 1.27 1.27)
				)
			)
		)
		(property "Value" ""
			(at 0 0 270)
			(layer "F.Fab")
			(effects
				(font
					(size 1.27 1.27)
				)
			)
		)
		(duplicate_pad_numbers_are_jumpers no)
		(fp_line
			(start -0.7874 0.4064)
			(end -0.7874 -0.4064)
			(stroke
				(width 0.1524)
				(type default)
			)
			(layer "F.SilkS")
		)
		(fp_line
			(start 0.7874 0.4064)
			(end -0.7874 0.4064)
			(stroke
				(width 0.1524)
				(type default)
			)
			(layer "F.SilkS")
		)
		(fp_line
			(start -0.7874 -0.4064)
			(end 0.7874 -0.4064)
			(stroke
				(width 0.1524)
				(type default)
			)
			(layer "F.SilkS")
		)
		(fp_line
			(start 0.7874 -0.4064)
			(end 0.7874 0.4064)
			(stroke
				(width 0.1524)
				(type default)
			)
			(layer "F.SilkS")
		)
		(fp_line
			(start -0.67945 0.3048)
			(end -0.67945 -0.305054)
			(stroke
				(width 0.1)
				(type default)
			)
			(layer "F.Fab")
		)
		(fp_line
			(start -0.12065 0.3048)
			(end -0.67945 0.3048)
			(stroke
				(width 0.1)
				(type default)
			)
			(layer "F.Fab")
		)
		(fp_line
			(start 0.120396 0.3048)
			(end 0.120396 0.2794)
			(stroke
				(width 0.1)
				(type default)
			)
			(layer "F.Fab")
		)
		(fp_line
			(start 0.67945 0.3048)
			(end 0.120396 0.3048)
			(stroke
				(width 0.1)
				(type default)
			)
			(layer "F.Fab")
		)
		(fp_line
			(start -0.12065 0.2794)
			(end -0.12065 0.3048)
			(stroke
				(width 0.1)
				(type default)
			)
			(layer "F.Fab")
		)
		(fp_line
			(start 0.120396 0.2794)
			(end -0.12065 0.2794)
			(stroke
				(width 0.1)
				(type default)
			)
			(layer "F.Fab")
		)
		(fp_line
			(start -0.12065 -0.2794)
			(end 0.12065 -0.2794)
			(stroke
				(width 0.1)
				(type default)
			)
			(layer "F.Fab")
		)
		(fp_line
			(start 0.12065 -0.2794)
			(end 0.12065 -0.3048)
			(stroke
				(width 0.1)
				(type default)
			)
			(layer "F.Fab")
		)
		(fp_line
			(start 0.12065 -0.3048)
			(end 0.67945 -0.3048)
			(stroke
				(width 0.1)
				(type default)
			)
			(layer "F.Fab")
		)
		(fp_line
			(start 0.67945 -0.3048)
			(end 0.67945 0.3048)
			(stroke
				(width 0.1)
				(type default)
			)
			(layer "F.Fab")
		)
		(fp_line
			(start -0.67945 -0.305054)
			(end -0.12065 -0.305054)
			(stroke
				(width 0.1)
				(type default)
			)
			(layer "F.Fab")
		)
		(fp_line
			(start -0.12065 -0.305054)
			(end -0.12065 -0.2794)
			(stroke
				(width 0.1)
				(type default)
			)
			(layer "F.Fab")
		)
		(pad "1" smd circle
			(at -0.40005 0 270)
			(size 0 0)
			(layers "F.Cu" "F.Mask" "F.Paste")
			(net "P3V3_AUX")
		)
		(pad "2" smd circle
			(at 0.40005 0 270)
			(size 0 0)
			(layers "F.Cu" "F.Mask" "F.Paste")
			(net "FM_GPU_HSC_EN_BUF_R")
		)
	)
	(footprint ""
		(layer "F.Cu")
		(at 15.58417 -70.194678)
		(property "Reference" "R3142"
			(at 0 0 0)
			(layer "F.SilkS")
			(hide yes)
			(effects
				(font
					(size 1.27 1.27)
				)
			)
		)
		(property "Value" ""
			(at 0 0 0)
			(layer "F.Fab")
			(effects
				(font
					(size 1.27 1.27)
				)
			)
		)
		(duplicate_pad_numbers_are_jumpers no)
		(fp_line
			(start -0.7874 -0.4064)
			(end 0.7874 -0.4064)
			(stroke
				(width 0.1524)
				(type default)
			)
			(layer "F.SilkS")
		)
		(fp_line
			(start -0.7874 0.4064)
			(end -0.7874 -0.4064)
			(stroke
				(width 0.1524)
				(type default)
			)
			(layer "F.SilkS")
		)
		(fp_line
			(start 0.7874 -0.4064)
			(end 0.7874 0.4064)
			(stroke
				(width 0.1524)
				(type default)
			)
			(layer "F.SilkS")
		)
		(fp_line
			(start 0.7874 0.4064)
			(end -0.7874 0.4064)
			(stroke
				(width 0.1524)
				(type default)
			)
			(layer "F.SilkS")
		)
		(fp_line
			(start -0.67945 -0.305054)
			(end -0.12065 -0.305054)
			(stroke
				(width 0.1)
				(type default)
			)
			(layer "F.Fab")
		)
		(fp_line
			(start -0.67945 0.3048)
			(end -0.67945 -0.305054)
			(stroke
				(width 0.1)
				(type default)
			)
			(layer "F.Fab")
		)
		(fp_line
			(start -0.12065 -0.305054)
			(end -0.12065 -0.2794)
			(stroke
				(width 0.1)
				(type default)
			)
			(layer "F.Fab")
		)
		(fp_line
			(start -0.12065 -0.2794)
			(end 0.12065 -0.2794)
			(stroke
				(width 0.1)
				(type default)
			)
			(layer "F.Fab")
		)
		(fp_line
			(start -0.12065 0.2794)
			(end -0.12065 0.3048)
			(stroke
				(width 0.1)
				(type default)
			)
			(layer "F.Fab")
		)
		(fp_line
			(start -0.12065 0.3048)
			(end -0.67945 0.3048)
			(stroke
				(width 0.1)
				(type default)
			)
			(layer "F.Fab")
		)
		(fp_line
			(start 0.120396 0.2794)
			(end -0.12065 0.2794)
			(stroke
				(width 0.1)
				(type default)
			)
			(layer "F.Fab")
		)
		(fp_line
			(start 0.120396 0.3048)
			(end 0.120396 0.2794)
			(stroke
				(width 0.1)
				(type default)
			)
			(layer "F.Fab")
		)
		(fp_line
			(start 0.12065 -0.3048)
			(end 0.67945 -0.3048)
			(stroke
				(width 0.1)
				(type default)
			)
			(layer "F.Fab")
		)
		(fp_line
			(start 0.12065 -0.2794)
			(end 0.12065 -0.3048)
			(stroke
				(width 0.1)
				(type default)
			)
			(layer "F.Fab")
		)
		(fp_line
			(start 0.67945 -0.3048)
			(end 0.67945 0.3048)
			(stroke
				(width 0.1)
				(type default)
			)
			(layer "F.Fab")
		)
		(fp_line
			(start 0.67945 0.3048)
			(end 0.120396 0.3048)
			(stroke
				(width 0.1)
				(type default)
			)
			(layer "F.Fab")
		)
		(pad "1" smd circle
			(at -0.40005 0)
			(size 0 0)
			(layers "F.Cu" "F.Mask" "F.Paste")
			(net "HP_LVC3_OCP_V3_2_PRSNT2_N_R")
		)
		(pad "2" smd circle
			(at 0.40005 0)
			(size 0 0)
			(layers "F.Cu" "F.Mask" "F.Paste")
			(net "HP_LVC3_OCP_V3_2_PRSNT2_PLD_N")
		)
	)
	(footprint ""
		(layer "F.Cu")
		(at 17.432782 -414.120584 180)
		(property "Reference" "PC6600"
			(at 0 0 180)
			(layer "F.SilkS")
			(hide yes)
			(effects
				(font
					(size 1.27 1.27)
				)
			)
		)
		(property "Value" ""
			(at 0 0 180)
			(layer "F.Fab")
			(effects
				(font
					(size 1.27 1.27)
				)
			)
		)
		(duplicate_pad_numbers_are_jumpers no)
		(fp_line
			(start 0.7874 0.4064)
			(end -0.7874 0.4064)
			(stroke
				(width 0.1524)
				(type default)
			)
			(layer "F.SilkS")
		)
		(fp_line
			(start 0.7874 -0.4064)
			(end 0.7874 0.4064)
			(stroke
				(width 0.1524)
				(type default)
			)
			(layer "F.SilkS")
		)
		(fp_line
			(start -0.7874 0.4064)
			(end -0.7874 -0.4064)
			(stroke
				(width 0.1524)
				(type default)
			)
			(layer "F.SilkS")
		)
		(fp_line
			(start -0.7874 -0.4064)
			(end 0.7874 -0.4064)
			(stroke
				(width 0.1524)
				(type default)
			)
			(layer "F.SilkS")
		)
		(fp_line
			(start 0.67945 0.3048)
			(end 0.120396 0.3048)
			(stroke
				(width 0.1)
				(type default)
			)
			(layer "F.Fab")
		)
		(fp_line
			(start 0.67945 -0.3048)
			(end 0.67945 0.3048)
			(stroke
				(width 0.1)
				(type default)
			)
			(layer "F.Fab")
		)
		(fp_line
			(start 0.12065 -0.2794)
			(end 0.12065 -0.3048)
			(stroke
				(width 0.1)
				(type default)
			)
			(layer "F.Fab")
		)
		(fp_line
			(start 0.12065 -0.3048)
			(end 0.67945 -0.3048)
			(stroke
				(width 0.1)
				(type default)
			)
			(layer "F.Fab")
		)
		(fp_line
			(start 0.120396 0.3048)
			(end 0.120396 0.2794)
			(stroke
				(width 0.1)
				(type default)
			)
			(layer "F.Fab")
		)
		(fp_line
			(start 0.120396 0.2794)
			(end -0.12065 0.2794)
			(stroke
				(width 0.1)
				(type default)
			)
			(layer "F.Fab")
		)
		(fp_line
			(start -0.12065 0.3048)
			(end -0.67945 0.3048)
			(stroke
				(width 0.1)
				(type default)
			)
			(layer "F.Fab")
		)
		(fp_line
			(start -0.12065 0.2794)
			(end -0.12065 0.3048)
			(stroke
				(width 0.1)
				(type default)
			)
			(layer "F.Fab")
		)
		(fp_line
			(start -0.12065 -0.2794)
			(end 0.12065 -0.2794)
			(stroke
				(width 0.1)
				(type default)
			)
			(layer "F.Fab")
		)
		(fp_line
			(start -0.12065 -0.305054)
			(end -0.12065 -0.2794)
			(stroke
				(width 0.1)
				(type default)
			)
			(layer "F.Fab")
		)
		(fp_line
			(start -0.67945 0.3048)
			(end -0.67945 -0.305054)
			(stroke
				(width 0.1)
				(type default)
			)
			(layer "F.Fab")
		)
		(fp_line
			(start -0.67945 -0.305054)
			(end -0.12065 -0.305054)
			(stroke
				(width 0.1)
				(type default)
			)
			(layer "F.Fab")
		)
		(pad "1" smd circle
			(at -0.40005 0 180)
			(size 0 0)
			(layers "F.Cu" "F.Mask" "F.Paste")
			(net "P0V9_RETIMER_CPU1_SENSE_R_P")
		)
		(pad "2" smd circle
			(at 0.40005 0 180)
			(size 0 0)
			(layers "F.Cu" "F.Mask" "F.Paste")
			(net "P0V9_RETIMER_CPU1_SENSE_SH_N")
		)
	)
	(footprint ""
		(layer "F.Cu")
		(at 458.346302 -405.972264)
		(property "Reference" "PC6581_2"
			(at 0 0 0)
			(layer "F.SilkS")
			(hide yes)
			(effects
				(font
					(size 1.27 1.27)
				)
			)
		)
		(property "Value" ""
			(at 0 0 0)
			(layer "F.Fab")
			(effects
				(font
					(size 1.27 1.27)
				)
			)
		)
		(duplicate_pad_numbers_are_jumpers no)
		(fp_line
			(start -1.524 -0.762)
			(end 1.524 -0.762)
			(stroke
				(width 0.1524)
				(type default)
			)
			(layer "F.SilkS")
		)
		(fp_line
			(start -1.524 0.762)
			(end -1.524 -0.762)
			(stroke
				(width 0.1524)
				(type default)
			)
			(layer "F.SilkS")
		)
		(fp_line
			(start 1.524 -0.762)
			(end 1.524 0.762)
			(stroke
				(width 0.1524)
				(type default)
			)
			(layer "F.SilkS")
		)
		(fp_line
			(start 1.524 0.762)
			(end -1.524 0.762)
			(stroke
				(width 0.1524)
				(type default)
			)
			(layer "F.SilkS")
		)
		(fp_line
			(start -1.1049 -0.724916)
			(end -1.1049 0.724916)
			(stroke
				(width 0.1)
				(type default)
			)
			(layer "F.Fab")
		)
		(fp_line
			(start -1.1049 0.724916)
			(end 1.1049 0.724916)
			(stroke
				(width 0.1)
				(type default)
			)
			(layer "F.Fab")
		)
		(fp_line
			(start 1.1049 -0.724916)
			(end -1.1049 -0.724916)
			(stroke
				(width 0.1)
				(type default)
			)
			(layer "F.Fab")
		)
		(fp_line
			(start 1.1049 0.724916)
			(end 1.1049 -0.724916)
			(stroke
				(width 0.1)
				(type default)
			)
			(layer "F.Fab")
		)
		(pad "1" smd rect
			(at -0.889 0 180)
			(size 1.016 1.27)
			(layers "F.Cu" "F.Mask" "F.Paste")
			(net "SW_P12V_AUX_P0V9_RETIMER_CPU0_FLT")
		)
		(pad "2" smd rect
			(at 0.889 0 180)
			(size 1.016 1.27)
			(layers "F.Cu" "F.Mask" "F.Paste")
			(net "GND")
		)
	)
	(footprint ""
		(layer "F.Cu")
		(at 180.528468 -48.053498)
		(property "Reference" "C9103"
			(at 0 0 0)
			(layer "F.SilkS")
			(hide yes)
			(effects
				(font
					(size 1.27 1.27)
				)
			)
		)
		(property "Value" ""
			(at 0 0 0)
			(layer "F.Fab")
			(effects
				(font
					(size 1.27 1.27)
				)
			)
		)
		(duplicate_pad_numbers_are_jumpers no)
		(fp_line
			(start -0.299974 -0.150114)
			(end 0.299974 -0.150114)
			(stroke
				(width 0.1)
				(type default)
			)
			(layer "F.Fab")
		)
		(fp_line
			(start -0.299974 0.150114)
			(end -0.299974 -0.150114)
			(stroke
				(width 0.1)
				(type default)
			)
			(layer "F.Fab")
		)
		(fp_line
			(start 0.299974 -0.150114)
			(end 0.299974 0.150114)
			(stroke
				(width 0.1)
				(type default)
			)
			(layer "F.Fab")
		)
		(fp_line
			(start 0.299974 0.150114)
			(end -0.299974 0.150114)
			(stroke
				(width 0.1)
				(type default)
			)
			(layer "F.Fab")
		)
		(pad "1" smd rect
			(at -0.2667 0)
			(size 0.3048 0.381)
			(layers "F.Cu" "F.Mask" "F.Paste")
			(net "P3E_CPU1_P4_TX_C_DN<1>")
		)
		(pad "2" smd rect
			(at 0.2667 0)
			(size 0.3048 0.381)
			(layers "F.Cu" "F.Mask" "F.Paste")
			(net "P3E_CPU1_P4_TX_DN<1>")
		)
	)
	(footprint ""
		(layer "F.Cu")
		(at 25.331166 -78.805024 -90)
		(property "Reference" "JP6001"
			(at -3.135122 6.727444 0)
			(unlocked yes)
			(layer "F.SilkS")
			(effects
				(font
					(size 0.7874 0.5842)
					(thickness 0.1524)
				)
				(justify left)
			)
		)
		(property "Value" ""
			(at 0 0 270)
			(layer "F.Fab")
			(effects
				(font
					(size 1.27 1.27)
				)
			)
		)
		(duplicate_pad_numbers_are_jumpers no)
		(fp_line
			(start -1.249934 6.400038)
			(end -1.249934 -1.320038)
			(stroke
				(width 0.1524)
				(type default)
			)
			(layer "F.SilkS")
		)
		(fp_line
			(start 1.249934 6.400038)
			(end -1.249934 6.400038)
			(stroke
				(width 0.1524)
				(type default)
			)
			(layer "F.SilkS")
		)
		(fp_line
			(start -1.249934 -1.320038)
			(end 1.249934 -1.320038)
			(stroke
				(width 0.1524)
				(type default)
			)
			(layer "F.SilkS")
		)
		(fp_line
			(start 1.249934 -1.320038)
			(end 1.249934 6.400038)
			(stroke
				(width 0.1524)
				(type default)
			)
			(layer "F.SilkS")
		)
		(fp_poly
			(pts
				(xy -2.5654 -0.556514) (xy -1.452372 0) (xy -2.5654 0.556514)
			)
			(stroke
				(width 0)
				(type default)
			)
			(fill yes)
			(layer "F.SilkS")
		)
		(fp_line
			(start -1.249934 6.400038)
			(end -1.249934 -1.320038)
			(stroke
				(width 0.1)
				(type default)
			)
			(layer "F.Fab")
		)
		(fp_line
			(start 1.249934 6.400038)
			(end -1.249934 6.400038)
			(stroke
				(width 0.1)
				(type default)
			)
			(layer "F.Fab")
		)
		(fp_line
			(start -1.249934 -1.320038)
			(end 1.249934 -1.320038)
			(stroke
				(width 0.1)
				(type default)
			)
			(layer "F.Fab")
		)
		(fp_line
			(start 1.249934 -1.320038)
			(end 1.249934 6.400038)
			(stroke
				(width 0.1)
				(type default)
			)
			(layer "F.Fab")
		)
		(fp_poly
			(pts
				(xy -2.5654 -0.556514) (xy -1.452372 0) (xy -2.5654 0.556514)
			)
			(stroke
				(width 0)
				(type default)
			)
			(fill yes)
			(layer "F.Fab")
		)
		(fp_text user "3"
			(at -1.778 5.13207 270)
			(unlocked yes)
			(layer "F.SilkS")
			(effects
				(font
					(size 0.7874 0.5842)
					(thickness 0.1524)
				)
			)
		)
		(fp_text user "3"
			(at -1.1557 5.18287 270)
			(unlocked yes)
			(layer "B.SilkS")
			(effects
				(font
					(size 0.7874 0.5842)
					(thickness 0.1524)
				)
				(justify mirror)
			)
		)
		(fp_text user "1"
			(at -1.143 0.02667 270)
			(unlocked yes)
			(layer "B.SilkS")
			(effects
				(font
					(size 0.7874 0.5842)
					(thickness 0.1524)
				)
				(justify mirror)
			)
		)
		(fp_text user "3"
			(at -1.1557 5.18287 270)
			(unlocked yes)
			(layer "B.Fab")
			(effects
				(font
					(size 0.7874 0.5842)
					(thickness 0.1524)
				)
				(justify mirror)
			)
		)
		(fp_text user "1"
			(at -1.143 0.02667 270)
			(unlocked yes)
			(layer "B.Fab")
			(effects
				(font
					(size 0.7874 0.5842)
					(thickness 0.1524)
				)
				(justify mirror)
			)
		)
		(fp_text user "3"
			(at -1.778 5.13207 270)
			(unlocked yes)
			(layer "F.Fab")
			(effects
				(font
					(size 0.7874 0.5842)
					(thickness 0.1524)
				)
			)
		)
		(pad "1" thru_hole rect
			(at 0 0 270)
			(size 1.5494 1.5494)
			(drill 1.0414)
			(layers "*.Cu" "*.Mask")
			(remove_unused_layers no)
			(net "PU_U160_EN_N")
			(clearance 0)
			(padstack
				(mode front_inner_back)
				(layer "Inner"
					(shape circle)
					(size 1.5494 1.5494)
					(clearance 0)
				)
				(layer "B.Cu"
					(shape rect)
					(size 1.5494 1.5494)
					(clearance 0)
				)
			)
		)
		(pad "2" thru_hole circle
			(at 0 2.54 270)
			(size 1.5494 1.5494)
			(drill 1.0414)
			(layers "*.Cu" "*.Mask")
			(remove_unused_layers no)
			(net "U160_EN_N")
			(clearance 0)
		)
		(pad "3" thru_hole circle
			(at 0 5.08 270)
			(size 1.5494 1.5494)
			(drill 1.0414)
			(layers "*.Cu" "*.Mask")
			(remove_unused_layers no)
			(net "PD_U160_EN_N")
			(clearance 0)
		)
	)
)
